(kicad_pcb
	(version 20260206)
	(generator "pcbnew")
	(generator_version "10.0")
	(general
		(thickness 1.6)
		(legacy_teardrops no)
	)
	(paper "A4")
	(title_block
		(title "03242023_DA0F0TMBIJ0_F0T_Motherboard_J_brd_V01_OCP.brd")
		(comment 1 "Grand Teton / footprints 3554-3558 of 6105")
	)
	(layers
		(0 "F.Cu" signal "TOP")
		(4 "In1.Cu" signal "GND")
		(6 "In2.Cu" signal "IN1")
		(8 "In3.Cu" signal "GND1")
		(10 "In4.Cu" signal "IN2")
		(12 "In5.Cu" signal "GND2")
		(14 "In6.Cu" signal "IN3")
		(16 "In7.Cu" signal "GND3")
		(18 "In8.Cu" signal "VCC")
		(20 "In9.Cu" signal "VCC1")
		(22 "In10.Cu" signal "GND4")
		(24 "In11.Cu" signal "IN4")
		(26 "In12.Cu" signal "GND5")
		(28 "In13.Cu" signal "IN5")
		(30 "In14.Cu" signal "GND6")
		(32 "In15.Cu" signal "IN6")
		(34 "In16.Cu" signal "GND7")
		(2 "B.Cu" signal "BOTTOM")
		(9 "F.Adhes" user "F.Adhesive")
		(11 "B.Adhes" user "B.Adhesive")
		(13 "F.Paste" user "Package Geometry/Pastemask Top")
		(15 "B.Paste" user "Package Geometry/Pastemask Bottom")
		(5 "F.SilkS" user "Ref Des/Silkscreen Top")
		(7 "B.SilkS" user "Ref Des/Silkscreen Bottom")
		(1 "F.Mask" user "Board Geometry/Soldermask Top")
		(3 "B.Mask" user "Board Geometry/Soldermask Bottom")
		(17 "Dwgs.User" user "User.Drawings")
		(19 "Cmts.User" user "User.Comments")
		(21 "Eco1.User" user "User.Eco1")
		(23 "Eco2.User" user "User.Eco2")
		(25 "Edge.Cuts" user "Board Geometry/Outline")
		(27 "Margin" user)
		(31 "F.CrtYd" user "Package Geometry/Place Bound Top")
		(29 "B.CrtYd" user "Package Geometry/Place Bound Bottom")
		(35 "F.Fab" user "Ref Des/Assembly Top")
		(33 "B.Fab" user "Ref Des/Assembly Bottom")
	)
	(footprint ""
		(layer "F.Cu")
		(at 204.68336 -67.20332)
		(property "Reference" "D144"
			(at -1.397 2.82067 0)
			(unlocked yes)
			(layer "F.SilkS")
			(effects
				(font
					(size 0.7874 0.5842)
					(thickness 0.1524)
				)
				(justify left)
			)
		)
		(property "Value" ""
			(at 0 0 0)
			(layer "F.Fab")
			(effects
				(font
					(size 1.27 1.27)
				)
			)
		)
		(duplicate_pad_numbers_are_jumpers no)
		(fp_line
			(start -1.3208 -0.5588)
			(end 1.3208 -0.5588)
			(stroke
				(width 0.1524)
				(type default)
			)
			(layer "F.SilkS")
		)
		(fp_line
			(start -1.3208 0.5588)
			(end -1.3208 -0.5588)
			(stroke
				(width 0.1524)
				(type default)
			)
			(layer "F.SilkS")
		)
		(fp_line
			(start 1.3208 -0.5588)
			(end 1.3208 0.5588)
			(stroke
				(width 0.1524)
				(type default)
			)
			(layer "F.SilkS")
		)
		(fp_line
			(start 1.3208 0.5588)
			(end -1.3208 0.5588)
			(stroke
				(width 0.1524)
				(type default)
			)
			(layer "F.SilkS")
		)
		(fp_line
			(start 1.4732 -0.5588)
			(end 1.4732 0.5588)
			(stroke
				(width 0.1524)
				(type default)
			)
			(layer "F.SilkS")
		)
		(fp_line
			(start 1.6256 0.5588)
			(end 1.6256 -0.5588)
			(stroke
				(width 0.1524)
				(type default)
			)
			(layer "F.SilkS")
		)
		(fp_line
			(start 1.778 -0.5588)
			(end 1.3208 -0.5588)
			(stroke
				(width 0.1524)
				(type default)
			)
			(layer "F.SilkS")
		)
		(fp_line
			(start 1.778 -0.5588)
			(end 1.778 0.5588)
			(stroke
				(width 0.1524)
				(type default)
			)
			(layer "F.SilkS")
		)
		(fp_line
			(start 1.778 0.5588)
			(end 1.3208 0.5588)
			(stroke
				(width 0.1524)
				(type default)
			)
			(layer "F.SilkS")
		)
		(fp_line
			(start -0.899922 -0.40005)
			(end 0.899922 -0.40005)
			(stroke
				(width 0.1)
				(type default)
			)
			(layer "F.Fab")
		)
		(fp_line
			(start -0.899922 0.40005)
			(end -0.899922 -0.40005)
			(stroke
				(width 0.1)
				(type default)
			)
			(layer "F.Fab")
		)
		(fp_line
			(start 0.899922 -0.40005)
			(end 0.899922 0.40005)
			(stroke
				(width 0.1)
				(type default)
			)
			(layer "F.Fab")
		)
		(fp_line
			(start 0.899922 0.40005)
			(end -0.899922 0.40005)
			(stroke
				(width 0.1)
				(type default)
			)
			(layer "F.Fab")
		)
		(fp_text user "+"
			(at -1.61036 0.99187 0)
			(unlocked yes)
			(layer "F.SilkS")
			(effects
				(font
					(size 1.905 1.4224)
					(thickness 0.1524)
				)
				(justify left)
			)
		)
		(fp_text user "-"
			(at 0.14224 1.01727 0)
			(unlocked yes)
			(layer "F.SilkS")
			(effects
				(font
					(size 1.905 1.4224)
					(thickness 0.1524)
				)
				(justify left)
			)
		)
		(fp_text user "+"
			(at -2.6162 -0.22225 0)
			(unlocked yes)
			(layer "F.Fab")
			(effects
				(font
					(size 1.905 1.4224)
					(thickness 0.1524)
				)
				(justify left)
			)
		)
		(fp_text user "-"
			(at 1.651 -0.22225 0)
			(unlocked yes)
			(layer "F.Fab")
			(effects
				(font
					(size 1.905 1.4224)
					(thickness 0.1524)
				)
				(justify left)
			)
		)
		(pad "A" smd rect
			(at -0.750062 0)
			(size 0.8128 0.8128)
			(layers "F.Cu" "F.Mask" "F.Paste")
			(net "LED_P12V_SCM_FAULT")
		)
		(pad "C" smd rect
			(at 0.750062 0)
			(size 0.8128 0.8128)
			(layers "F.Cu" "F.Mask" "F.Paste")
			(net "LED_P12V_SCM_FAULT_D2")
		)
	)
	(footprint ""
		(layer "F.Cu")
		(at 300.733714 -14.506194)
		(property "Reference" "R4189"
			(at 0 0 0)
			(layer "F.SilkS")
			(hide yes)
			(effects
				(font
					(size 1.27 1.27)
				)
			)
		)
		(property "Value" ""
			(at 0 0 0)
			(layer "F.Fab")
			(effects
				(font
					(size 1.27 1.27)
				)
			)
		)
		(duplicate_pad_numbers_are_jumpers no)
		(fp_line
			(start -0.7874 -0.4064)
			(end 0.7874 -0.4064)
			(stroke
				(width 0.1524)
				(type default)
			)
			(layer "F.SilkS")
		)
		(fp_line
			(start -0.7874 0.4064)
			(end -0.7874 -0.4064)
			(stroke
				(width 0.1524)
				(type default)
			)
			(layer "F.SilkS")
		)
		(fp_line
			(start 0.7874 -0.4064)
			(end 0.7874 0.4064)
			(stroke
				(width 0.1524)
				(type default)
			)
			(layer "F.SilkS")
		)
		(fp_line
			(start 0.7874 0.4064)
			(end -0.7874 0.4064)
			(stroke
				(width 0.1524)
				(type default)
			)
			(layer "F.SilkS")
		)
		(fp_line
			(start -0.67945 -0.305054)
			(end -0.12065 -0.305054)
			(stroke
				(width 0.1)
				(type default)
			)
			(layer "F.Fab")
		)
		(fp_line
			(start -0.67945 0.3048)
			(end -0.67945 -0.305054)
			(stroke
				(width 0.1)
				(type default)
			)
			(layer "F.Fab")
		)
		(fp_line
			(start -0.12065 -0.305054)
			(end -0.12065 -0.2794)
			(stroke
				(width 0.1)
				(type default)
			)
			(layer "F.Fab")
		)
		(fp_line
			(start -0.12065 -0.2794)
			(end 0.12065 -0.2794)
			(stroke
				(width 0.1)
				(type default)
			)
			(layer "F.Fab")
		)
		(fp_line
			(start -0.12065 0.2794)
			(end -0.12065 0.3048)
			(stroke
				(width 0.1)
				(type default)
			)
			(layer "F.Fab")
		)
		(fp_line
			(start -0.12065 0.3048)
			(end -0.67945 0.3048)
			(stroke
				(width 0.1)
				(type default)
			)
			(layer "F.Fab")
		)
		(fp_line
			(start 0.120396 0.2794)
			(end -0.12065 0.2794)
			(stroke
				(width 0.1)
				(type default)
			)
			(layer "F.Fab")
		)
		(fp_line
			(start 0.120396 0.3048)
			(end 0.120396 0.2794)
			(stroke
				(width 0.1)
				(type default)
			)
			(layer "F.Fab")
		)
		(fp_line
			(start 0.12065 -0.3048)
			(end 0.67945 -0.3048)
			(stroke
				(width 0.1)
				(type default)
			)
			(layer "F.Fab")
		)
		(fp_line
			(start 0.12065 -0.2794)
			(end 0.12065 -0.3048)
			(stroke
				(width 0.1)
				(type default)
			)
			(layer "F.Fab")
		)
		(fp_line
			(start 0.67945 -0.3048)
			(end 0.67945 0.3048)
			(stroke
				(width 0.1)
				(type default)
			)
			(layer "F.Fab")
		)
		(fp_line
			(start 0.67945 0.3048)
			(end 0.120396 0.3048)
			(stroke
				(width 0.1)
				(type default)
			)
			(layer "F.Fab")
		)
		(pad "1" smd circle
			(at -0.40005 0)
			(size 0 0)
			(layers "F.Cu" "F.Mask" "F.Paste")
			(net "U271_1_ADD2")
		)
		(pad "2" smd circle
			(at 0.40005 0)
			(size 0 0)
			(layers "F.Cu" "F.Mask" "F.Paste")
			(net "GND")
		)
	)
	(footprint ""
		(layer "F.Cu")
		(at 349.0849 -63.312548)
		(property "Reference" "C142"
			(at 0 0 0)
			(layer "F.SilkS")
			(hide yes)
			(effects
				(font
					(size 1.27 1.27)
				)
			)
		)
		(property "Value" ""
			(at 0 0 0)
			(layer "F.Fab")
			(effects
				(font
					(size 1.27 1.27)
				)
			)
		)
		(duplicate_pad_numbers_are_jumpers no)
		(fp_line
			(start -0.299974 -0.150114)
			(end 0.299974 -0.150114)
			(stroke
				(width 0.1)
				(type default)
			)
			(layer "F.Fab")
		)
		(fp_line
			(start -0.299974 0.150114)
			(end -0.299974 -0.150114)
			(stroke
				(width 0.1)
				(type default)
			)
			(layer "F.Fab")
		)
		(fp_line
			(start 0.299974 -0.150114)
			(end 0.299974 0.150114)
			(stroke
				(width 0.1)
				(type default)
			)
			(layer "F.Fab")
		)
		(fp_line
			(start 0.299974 0.150114)
			(end -0.299974 0.150114)
			(stroke
				(width 0.1)
				(type default)
			)
			(layer "F.Fab")
		)
		(pad "1" smd rect
			(at -0.2667 0)
			(size 0.3048 0.381)
			(layers "F.Cu" "F.Mask" "F.Paste")
			(net "DMI_CPU0_PCH_TX_C_DP<6>")
		)
		(pad "2" smd rect
			(at 0.2667 0)
			(size 0.3048 0.381)
			(layers "F.Cu" "F.Mask" "F.Paste")
			(net "DMI_CPU0_PCH_TX_DP<6>")
		)
		(zone
			(layer "In1.Cu")
			(hatch none 0.5)
			(connect_pads
				(clearance 0)
			)
			(min_thickness 0.25)
			(keepout
				(tracks not_allowed)
				(vias allowed)
				(pads allowed)
				(copperpour not_allowed)
				(footprints allowed)
			)
			(placement
				(enabled no)
				(sheetname "")
			)
			(fill
				(thermal_gap 0.5)
				(thermal_bridge_width 0.5)
				(island_removal_mode 0)
			)
			(polygon
				(pts
					(arc
						(start 348.6912 -63.071248)
						(mid 348.637318 -63.093566)
						(end 348.615 -63.147448)
					)
					(arc
						(start 348.615 -63.477648)
						(mid 348.637318 -63.53153)
						(end 348.6912 -63.553848)
					)
					(arc
						(start 348.9452 -63.553848)
						(mid 348.999082 -63.53153)
						(end 349.0214 -63.477648)
					)
					(arc
						(start 349.0214 -63.147448)
						(mid 348.999082 -63.093566)
						(end 348.9452 -63.071248)
					)
				)
			)
		)
		(zone
			(layer "In1.Cu")
			(hatch none 0.5)
			(connect_pads
				(clearance 0)
			)
			(min_thickness 0.25)
			(keepout
				(tracks not_allowed)
				(vias allowed)
				(pads allowed)
				(copperpour not_allowed)
				(footprints allowed)
			)
			(placement
				(enabled no)
				(sheetname "")
			)
			(fill
				(thermal_gap 0.5)
				(thermal_bridge_width 0.5)
				(island_removal_mode 0)
			)
			(polygon
				(pts
					(arc
						(start 349.2246 -63.071248)
						(mid 349.170718 -63.093566)
						(end 349.1484 -63.147448)
					)
					(arc
						(start 349.1484 -63.477648)
						(mid 349.170718 -63.53153)
						(end 349.2246 -63.553848)
					)
					(arc
						(start 349.4786 -63.553848)
						(mid 349.532482 -63.53153)
						(end 349.5548 -63.477648)
					)
					(arc
						(start 349.5548 -63.147448)
						(mid 349.532482 -63.093566)
						(end 349.4786 -63.071248)
					)
				)
			)
		)
	)
	(footprint ""
		(layer "F.Cu")
		(at 22.356826 -174.113952)
		(property "Reference" "PC238"
			(at 0 0 0)
			(layer "F.SilkS")
			(hide yes)
			(effects
				(font
					(size 1.27 1.27)
				)
			)
		)
		(property "Value" ""
			(at 0 0 0)
			(layer "F.Fab")
			(effects
				(font
					(size 1.27 1.27)
				)
			)
		)
		(duplicate_pad_numbers_are_jumpers no)
		(fp_line
			(start -0.7874 -0.4064)
			(end 0.7874 -0.4064)
			(stroke
				(width 0.1524)
				(type default)
			)
			(layer "F.SilkS")
		)
		(fp_line
			(start -0.7874 0.4064)
			(end -0.7874 -0.4064)
			(stroke
				(width 0.1524)
				(type default)
			)
			(layer "F.SilkS")
		)
		(fp_line
			(start 0.7874 -0.4064)
			(end 0.7874 0.4064)
			(stroke
				(width 0.1524)
				(type default)
			)
			(layer "F.SilkS")
		)
		(fp_line
			(start 0.7874 0.4064)
			(end -0.7874 0.4064)
			(stroke
				(width 0.1524)
				(type default)
			)
			(layer "F.SilkS")
		)
		(fp_line
			(start -0.67945 -0.305054)
			(end -0.12065 -0.305054)
			(stroke
				(width 0.1)
				(type default)
			)
			(layer "F.Fab")
		)
		(fp_line
			(start -0.67945 0.3048)
			(end -0.67945 -0.305054)
			(stroke
				(width 0.1)
				(type default)
			)
			(layer "F.Fab")
		)
		(fp_line
			(start -0.12065 -0.305054)
			(end -0.12065 -0.2794)
			(stroke
				(width 0.1)
				(type default)
			)
			(layer "F.Fab")
		)
		(fp_line
			(start -0.12065 -0.2794)
			(end 0.12065 -0.2794)
			(stroke
				(width 0.1)
				(type default)
			)
			(layer "F.Fab")
		)
		(fp_line
			(start -0.12065 0.2794)
			(end -0.12065 0.3048)
			(stroke
				(width 0.1)
				(type default)
			)
			(layer "F.Fab")
		)
		(fp_line
			(start -0.12065 0.3048)
			(end -0.67945 0.3048)
			(stroke
				(width 0.1)
				(type default)
			)
			(layer "F.Fab")
		)
		(fp_line
			(start 0.120396 0.2794)
			(end -0.12065 0.2794)
			(stroke
				(width 0.1)
				(type default)
			)
			(layer "F.Fab")
		)
		(fp_line
			(start 0.120396 0.3048)
			(end 0.120396 0.2794)
			(stroke
				(width 0.1)
				(type default)
			)
			(layer "F.Fab")
		)
		(fp_line
			(start 0.12065 -0.3048)
			(end 0.67945 -0.3048)
			(stroke
				(width 0.1)
				(type default)
			)
			(layer "F.Fab")
		)
		(fp_line
			(start 0.12065 -0.2794)
			(end 0.12065 -0.3048)
			(stroke
				(width 0.1)
				(type default)
			)
			(layer "F.Fab")
		)
		(fp_line
			(start 0.67945 -0.3048)
			(end 0.67945 0.3048)
			(stroke
				(width 0.1)
				(type default)
			)
			(layer "F.Fab")
		)
		(fp_line
			(start 0.67945 0.3048)
			(end 0.120396 0.3048)
			(stroke
				(width 0.1)
				(type default)
			)
			(layer "F.Fab")
		)
		(pad "1" smd circle
			(at -0.40005 0)
			(size 0 0)
			(layers "F.Cu" "F.Mask" "F.Paste")
			(net "PVNN_MAIN_CPU1_FB")
		)
		(pad "2" smd circle
			(at 0.40005 0)
			(size 0 0)
			(layers "F.Cu" "F.Mask" "F.Paste")
			(net "PVNN_MAIN_CPU1_FB_RC")
		)
	)
	(footprint ""
		(layer "F.Cu")
		(at 260.561582 -76.533502)
		(property "Reference" "PR1328"
			(at 0 0 0)
			(layer "F.SilkS")
			(hide yes)
			(effects
				(font
					(size 1.27 1.27)
				)
			)
		)
		(property "Value" ""
			(at 0 0 0)
			(layer "F.Fab")
			(effects
				(font
					(size 1.27 1.27)
				)
			)
		)
		(duplicate_pad_numbers_are_jumpers no)
		(fp_line
			(start -0.7874 -0.4064)
			(end 0.7874 -0.4064)
			(stroke
				(width 0.1524)
				(type default)
			)
			(layer "F.SilkS")
		)
		(fp_line
			(start -0.7874 0.4064)
			(end -0.7874 -0.4064)
			(stroke
				(width 0.1524)
				(type default)
			)
			(layer "F.SilkS")
		)
		(fp_line
			(start 0.7874 -0.4064)
			(end 0.7874 0.4064)
			(stroke
				(width 0.1524)
				(type default)
			)
			(layer "F.SilkS")
		)
		(fp_line
			(start 0.7874 0.4064)
			(end -0.7874 0.4064)
			(stroke
				(width 0.1524)
				(type default)
			)
			(layer "F.SilkS")
		)
		(fp_line
			(start -0.67945 -0.305054)
			(end -0.12065 -0.305054)
			(stroke
				(width 0.1)
				(type default)
			)
			(layer "F.Fab")
		)
		(fp_line
			(start -0.67945 0.3048)
			(end -0.67945 -0.305054)
			(stroke
				(width 0.1)
				(type default)
			)
			(layer "F.Fab")
		)
		(fp_line
			(start -0.12065 -0.305054)
			(end -0.12065 -0.2794)
			(stroke
				(width 0.1)
				(type default)
			)
			(layer "F.Fab")
		)
		(fp_line
			(start -0.12065 -0.2794)
			(end 0.12065 -0.2794)
			(stroke
				(width 0.1)
				(type default)
			)
			(layer "F.Fab")
		)
		(fp_line
			(start -0.12065 0.2794)
			(end -0.12065 0.3048)
			(stroke
				(width 0.1)
				(type default)
			)
			(layer "F.Fab")
		)
		(fp_line
			(start -0.12065 0.3048)
			(end -0.67945 0.3048)
			(stroke
				(width 0.1)
				(type default)
			)
			(layer "F.Fab")
		)
		(fp_line
			(start 0.120396 0.2794)
			(end -0.12065 0.2794)
			(stroke
				(width 0.1)
				(type default)
			)
			(layer "F.Fab")
		)
		(fp_line
			(start 0.120396 0.3048)
			(end 0.120396 0.2794)
			(stroke
				(width 0.1)
				(type default)
			)
			(layer "F.Fab")
		)
		(fp_line
			(start 0.12065 -0.3048)
			(end 0.67945 -0.3048)
			(stroke
				(width 0.1)
				(type default)
			)
			(layer "F.Fab")
		)
		(fp_line
			(start 0.12065 -0.2794)
			(end 0.12065 -0.3048)
			(stroke
				(width 0.1)
				(type default)
			)
			(layer "F.Fab")
		)
		(fp_line
			(start 0.67945 -0.3048)
			(end 0.67945 0.3048)
			(stroke
				(width 0.1)
				(type default)
			)
			(layer "F.Fab")
		)
		(fp_line
			(start 0.67945 0.3048)
			(end 0.120396 0.3048)
			(stroke
				(width 0.1)
				(type default)
			)
			(layer "F.Fab")
		)
		(pad "1" smd circle
			(at -0.40005 0)
			(size 0 0)
			(layers "F.Cu" "F.Mask" "F.Paste")
			(net "P1V05_PCH_AUX_FB")
		)
		(pad "2" smd circle
			(at 0.40005 0)
			(size 0 0)
			(layers "F.Cu" "F.Mask" "F.Paste")
			(net "SH_P1V05_PCH_AUX_P")
		)
	)
)
